(kicad_pcb
	(version 20260206)
	(generator "pcbnew")
	(generator_version "10.0")
	(general
		(thickness 1.6)
		(legacy_teardrops no)
	)
	(paper "A4")
	(title_block
		(title "01162023_DA0F0TEBIF0_F0T_Expander_BD_F_brd_V02_OCP.brd")
		(comment 1 "Grand Teton / footprints 9248-9257 of 9728")
	)
	(layers
		(0 "F.Cu" signal "TOP")
		(4 "In1.Cu" signal "GND")
		(6 "In2.Cu" signal "VCC")
		(8 "In3.Cu" signal "VCC1")
		(10 "In4.Cu" signal "GND1")
		(12 "In5.Cu" signal "IN1")
		(14 "In6.Cu" signal "GND2")
		(16 "In7.Cu" signal "IN2")
		(18 "In8.Cu" signal "GND3")
		(20 "In9.Cu" signal "IN3")
		(22 "In10.Cu" signal "GND4")
		(24 "In11.Cu" signal "IN4")
		(26 "In12.Cu" signal "GND5")
		(28 "In13.Cu" signal "IN5")
		(30 "In14.Cu" signal "GND6")
		(32 "In15.Cu" signal "IN6")
		(34 "In16.Cu" signal "GND7")
		(2 "B.Cu" signal "BOTTOM")
		(9 "F.Adhes" user "F.Adhesive")
		(11 "B.Adhes" user "B.Adhesive")
		(13 "F.Paste" user "Package Geometry/Pastemask Top")
		(15 "B.Paste" user "Package Geometry/Pastemask Bottom")
		(5 "F.SilkS" user "Ref Des/Silkscreen Top")
		(7 "B.SilkS" user "Ref Des/Silkscreen Bottom")
		(1 "F.Mask" user "Board Geometry/Soldermask Top")
		(3 "B.Mask" user "Board Geometry/Soldermask Bottom")
		(17 "Dwgs.User" user "User.Drawings")
		(19 "Cmts.User" user "User.Comments")
		(21 "Eco1.User" user "User.Eco1")
		(23 "Eco2.User" user "User.Eco2")
		(25 "Edge.Cuts" user "Board Geometry/Outline")
		(27 "Margin" user)
		(31 "F.CrtYd" user "Package Geometry/Place Bound Top")
		(29 "B.CrtYd" user "Package Geometry/Place Bound Bottom")
		(35 "F.Fab" user "Ref Des/Assembly Top")
		(33 "B.Fab" user "Ref Des/Assembly Bottom")
	)
	(footprint ""
		(layer "B.Cu")
		(at 408.75204 -296.3926 180)
		(property "Reference" "C1876"
			(at 0 0 0)
			(layer "B.SilkS")
			(hide yes)
			(effects
				(font
					(size 1.27 1.27)
				)
				(justify mirror)
			)
		)
		(property "Value" ""
			(at 0 0 0)
			(layer "B.Fab")
			(effects
				(font
					(size 1.27 1.27)
				)
				(justify mirror)
			)
		)
		(duplicate_pad_numbers_are_jumpers no)
		(fp_line
			(start 0.299974 0.150114)
			(end 0.299974 -0.150114)
			(stroke
				(width 0.1)
				(type default)
			)
			(layer "B.Fab")
		)
		(fp_line
			(start 0.299974 -0.150114)
			(end -0.299974 -0.150114)
			(stroke
				(width 0.1)
				(type default)
			)
			(layer "B.Fab")
		)
		(fp_line
			(start -0.299974 0.150114)
			(end 0.299974 0.150114)
			(stroke
				(width 0.1)
				(type default)
			)
			(layer "B.Fab")
		)
		(fp_line
			(start -0.299974 -0.150114)
			(end -0.299974 0.150114)
			(stroke
				(width 0.1)
				(type default)
			)
			(layer "B.Fab")
		)
		(pad "1" smd rect
			(at 0.2667 0)
			(size 0.3048 0.381)
			(layers "B.Cu" "B.Mask" "B.Paste")
			(net "P0V8_PEX3")
		)
		(pad "2" smd rect
			(at -0.2667 0)
			(size 0.3048 0.381)
			(layers "B.Cu" "B.Mask" "B.Paste")
			(net "GND")
		)
	)
	(footprint ""
		(layer "B.Cu")
		(at 183.3499 -303.499774 -90)
		(property "Reference" "C3112"
			(at 0 0 90)
			(layer "B.SilkS")
			(hide yes)
			(effects
				(font
					(size 1.27 1.27)
				)
				(justify mirror)
			)
		)
		(property "Value" ""
			(at 0 0 90)
			(layer "B.Fab")
			(effects
				(font
					(size 1.27 1.27)
				)
				(justify mirror)
			)
		)
		(duplicate_pad_numbers_are_jumpers no)
		(fp_line
			(start -0.299974 0.150114)
			(end 0.299974 0.150114)
			(stroke
				(width 0.1)
				(type default)
			)
			(layer "B.Fab")
		)
		(fp_line
			(start 0.299974 0.150114)
			(end 0.299974 -0.150114)
			(stroke
				(width 0.1)
				(type default)
			)
			(layer "B.Fab")
		)
		(fp_line
			(start -0.299974 -0.150114)
			(end -0.299974 0.150114)
			(stroke
				(width 0.1)
				(type default)
			)
			(layer "B.Fab")
		)
		(fp_line
			(start 0.299974 -0.150114)
			(end -0.299974 -0.150114)
			(stroke
				(width 0.1)
				(type default)
			)
			(layer "B.Fab")
		)
		(pad "1" smd rect
			(at 0.2667 0 90)
			(size 0.3048 0.381)
			(layers "B.Cu" "B.Mask" "B.Paste")
			(net "P1V25_PEX1")
		)
		(pad "2" smd rect
			(at -0.2667 0 90)
			(size 0.3048 0.381)
			(layers "B.Cu" "B.Mask" "B.Paste")
			(net "GND")
		)
	)
	(footprint ""
		(layer "B.Cu")
		(at 231.81691 -90.197178 90)
		(property "Reference" "C2618"
			(at 0 0 90)
			(layer "B.SilkS")
			(hide yes)
			(effects
				(font
					(size 1.27 1.27)
				)
				(justify mirror)
			)
		)
		(property "Value" ""
			(at 0 0 90)
			(layer "B.Fab")
			(effects
				(font
					(size 1.27 1.27)
				)
				(justify mirror)
			)
		)
		(duplicate_pad_numbers_are_jumpers no)
		(fp_line
			(start 0.7874 -0.4064)
			(end -0.7874 -0.4064)
			(stroke
				(width 0.1524)
				(type default)
			)
			(layer "B.SilkS")
		)
		(fp_line
			(start -0.7874 -0.4064)
			(end -0.7874 0.4064)
			(stroke
				(width 0.1524)
				(type default)
			)
			(layer "B.SilkS")
		)
		(fp_line
			(start 0.7874 0.4064)
			(end 0.7874 -0.4064)
			(stroke
				(width 0.1524)
				(type default)
			)
			(layer "B.SilkS")
		)
		(fp_line
			(start -0.7874 0.4064)
			(end 0.7874 0.4064)
			(stroke
				(width 0.1524)
				(type default)
			)
			(layer "B.SilkS")
		)
		(fp_line
			(start 0.67945 -0.305054)
			(end 0.12065 -0.305054)
			(stroke
				(width 0.1)
				(type default)
			)
			(layer "B.Fab")
		)
		(fp_line
			(start 0.12065 -0.305054)
			(end 0.12065 -0.2794)
			(stroke
				(width 0.1)
				(type default)
			)
			(layer "B.Fab")
		)
		(fp_line
			(start -0.12065 -0.3048)
			(end -0.67945 -0.3048)
			(stroke
				(width 0.1)
				(type default)
			)
			(layer "B.Fab")
		)
		(fp_line
			(start -0.67945 -0.3048)
			(end -0.67945 0.3048)
			(stroke
				(width 0.1)
				(type default)
			)
			(layer "B.Fab")
		)
		(fp_line
			(start 0.12065 -0.2794)
			(end -0.12065 -0.2794)
			(stroke
				(width 0.1)
				(type default)
			)
			(layer "B.Fab")
		)
		(fp_line
			(start -0.12065 -0.2794)
			(end -0.12065 -0.3048)
			(stroke
				(width 0.1)
				(type default)
			)
			(layer "B.Fab")
		)
		(fp_line
			(start 0.12065 0.2794)
			(end 0.12065 0.3048)
			(stroke
				(width 0.1)
				(type default)
			)
			(layer "B.Fab")
		)
		(fp_line
			(start -0.120396 0.2794)
			(end 0.12065 0.2794)
			(stroke
				(width 0.1)
				(type default)
			)
			(layer "B.Fab")
		)
		(fp_line
			(start 0.67945 0.3048)
			(end 0.67945 -0.305054)
			(stroke
				(width 0.1)
				(type default)
			)
			(layer "B.Fab")
		)
		(fp_line
			(start 0.12065 0.3048)
			(end 0.67945 0.3048)
			(stroke
				(width 0.1)
				(type default)
			)
			(layer "B.Fab")
		)
		(fp_line
			(start -0.120396 0.3048)
			(end -0.120396 0.2794)
			(stroke
				(width 0.1)
				(type default)
			)
			(layer "B.Fab")
		)
		(fp_line
			(start -0.67945 0.3048)
			(end -0.120396 0.3048)
			(stroke
				(width 0.1)
				(type default)
			)
			(layer "B.Fab")
		)
		(pad "1" smd circle
			(at 0.40005 0 270)
			(size 0 0)
			(layers "B.Cu" "B.Mask" "B.Paste")
			(net "P3V3_PEX_USB_HUB")
		)
		(pad "2" smd circle
			(at -0.40005 0 270)
			(size 0 0)
			(layers "B.Cu" "B.Mask" "B.Paste")
			(net "GND")
		)
	)
	(footprint ""
		(layer "B.Cu")
		(at 169.099992 -301.599854 -90)
		(property "Reference" "C1445"
			(at 0 0 90)
			(layer "B.SilkS")
			(hide yes)
			(effects
				(font
					(size 1.27 1.27)
				)
				(justify mirror)
			)
		)
		(property "Value" ""
			(at 0 0 90)
			(layer "B.Fab")
			(effects
				(font
					(size 1.27 1.27)
				)
				(justify mirror)
			)
		)
		(duplicate_pad_numbers_are_jumpers no)
		(fp_line
			(start -0.299974 0.150114)
			(end 0.299974 0.150114)
			(stroke
				(width 0.1)
				(type default)
			)
			(layer "B.Fab")
		)
		(fp_line
			(start 0.299974 0.150114)
			(end 0.299974 -0.150114)
			(stroke
				(width 0.1)
				(type default)
			)
			(layer "B.Fab")
		)
		(fp_line
			(start -0.299974 -0.150114)
			(end -0.299974 0.150114)
			(stroke
				(width 0.1)
				(type default)
			)
			(layer "B.Fab")
		)
		(fp_line
			(start 0.299974 -0.150114)
			(end -0.299974 -0.150114)
			(stroke
				(width 0.1)
				(type default)
			)
			(layer "B.Fab")
		)
		(pad "1" smd rect
			(at 0.2667 0 90)
			(size 0.3048 0.381)
			(layers "B.Cu" "B.Mask" "B.Paste")
			(net "P0V8_SERDES_VDDA_PEX1")
		)
		(pad "2" smd rect
			(at -0.2667 0 90)
			(size 0.3048 0.381)
			(layers "B.Cu" "B.Mask" "B.Paste")
			(net "GND")
		)
	)
	(footprint ""
		(layer "B.Cu")
		(at 53.949854 -292.099746 90)
		(property "Reference" "C1225"
			(at 0 0 90)
			(layer "B.SilkS")
			(hide yes)
			(effects
				(font
					(size 1.27 1.27)
				)
				(justify mirror)
			)
		)
		(property "Value" ""
			(at 0 0 90)
			(layer "B.Fab")
			(effects
				(font
					(size 1.27 1.27)
				)
				(justify mirror)
			)
		)
		(duplicate_pad_numbers_are_jumpers no)
		(fp_line
			(start 0.299974 -0.150114)
			(end -0.299974 -0.150114)
			(stroke
				(width 0.1)
				(type default)
			)
			(layer "B.Fab")
		)
		(fp_line
			(start -0.299974 -0.150114)
			(end -0.299974 0.150114)
			(stroke
				(width 0.1)
				(type default)
			)
			(layer "B.Fab")
		)
		(fp_line
			(start 0.299974 0.150114)
			(end 0.299974 -0.150114)
			(stroke
				(width 0.1)
				(type default)
			)
			(layer "B.Fab")
		)
		(fp_line
			(start -0.299974 0.150114)
			(end 0.299974 0.150114)
			(stroke
				(width 0.1)
				(type default)
			)
			(layer "B.Fab")
		)
		(pad "1" smd rect
			(at 0.2667 0 270)
			(size 0.3048 0.381)
			(layers "B.Cu" "B.Mask" "B.Paste")
			(net "P0V8_SERDES_VDDA_PEX0")
		)
		(pad "2" smd rect
			(at -0.2667 0 270)
			(size 0.3048 0.381)
			(layers "B.Cu" "B.Mask" "B.Paste")
			(net "GND")
		)
	)
	(footprint ""
		(layer "B.Cu")
		(at 302.78959 -245.912386 -90)
		(property "Reference" "U318"
			(at 2.108708 2.230628 270)
			(unlocked yes)
			(layer "B.SilkS")
			(effects
				(font
					(size 0.7874 0.5842)
					(thickness 0.1524)
				)
				(justify mirror)
			)
		)
		(property "Value" ""
			(at 0 0 90)
			(layer "B.Fab")
			(effects
				(font
					(size 1.27 1.27)
				)
				(justify mirror)
			)
		)
		(duplicate_pad_numbers_are_jumpers no)
		(fp_line
			(start -1.463548 1.549908)
			(end 1.463548 1.549908)
			(stroke
				(width 0.1524)
				(type default)
			)
			(layer "B.SilkS")
		)
		(fp_line
			(start 1.463548 1.549908)
			(end 1.463548 -1.549908)
			(stroke
				(width 0.1524)
				(type default)
			)
			(layer "B.SilkS")
		)
		(fp_line
			(start 0 -0.762)
			(end -0.762 -1.549908)
			(stroke
				(width 0.1524)
				(type default)
			)
			(layer "B.SilkS")
		)
		(fp_line
			(start -1.463548 -1.549908)
			(end -1.463548 1.549908)
			(stroke
				(width 0.1524)
				(type default)
			)
			(layer "B.SilkS")
		)
		(fp_line
			(start -0.762 -1.549908)
			(end -1.463548 -1.549908)
			(stroke
				(width 0.1524)
				(type default)
			)
			(layer "B.SilkS")
		)
		(fp_line
			(start 0.787908 -1.549908)
			(end 0 -0.762)
			(stroke
				(width 0.1524)
				(type default)
			)
			(layer "B.SilkS")
		)
		(fp_line
			(start 1.463548 -1.549908)
			(end 0.787908 -1.549908)
			(stroke
				(width 0.1524)
				(type default)
			)
			(layer "B.SilkS")
		)
		(fp_poly
			(pts
				(xy 3.712718 -0.616204) (xy 3.055366 -0.835406) (xy 3.274568 -0.178054)
			)
			(stroke
				(width 0)
				(type default)
			)
			(fill yes)
			(layer "B.SilkS")
		)
		(fp_line
			(start -1.549908 1.549908)
			(end 1.549908 1.549908)
			(stroke
				(width 0.1)
				(type default)
			)
			(layer "B.Fab")
		)
		(fp_line
			(start 1.549908 1.549908)
			(end 1.549908 -1.549908)
			(stroke
				(width 0.1)
				(type default)
			)
			(layer "B.Fab")
		)
		(fp_line
			(start -1.549908 -1.549908)
			(end -1.549908 1.549908)
			(stroke
				(width 0.1)
				(type default)
			)
			(layer "B.Fab")
		)
		(fp_line
			(start 1.549908 -1.549908)
			(end -1.549908 -1.549908)
			(stroke
				(width 0.1)
				(type default)
			)
			(layer "B.Fab")
		)
		(fp_poly
			(pts
				(xy 3.4798 -1.359916) (xy 2.86004 -1.050036) (xy 3.4798 -0.740156)
			)
			(stroke
				(width 0)
				(type default)
			)
			(fill yes)
			(layer "B.Fab")
		)
		(pad "1" smd rect
			(at 2.175002 -1.050036)
			(size 0.6096 1.1684)
			(layers "B.Cu" "B.Mask" "B.Paste")
			(net "P3V3_AUX")
		)
		(pad "2" smd rect
			(at 2.175002 -0.32512)
			(size 0.4318 1.1684)
			(layers "B.Cu" "B.Mask" "B.Paste")
			(net "SMB_MB_BMC_ISO_SCL")
		)
		(pad "3" smd rect
			(at 2.175002 0.32512)
			(size 0.4318 1.1684)
			(layers "B.Cu" "B.Mask" "B.Paste")
			(net "SMB_MB_BMC_ISO_SDA")
		)
		(pad "4" smd rect
			(at 2.175002 1.050036)
			(size 0.6096 1.1684)
			(layers "B.Cu" "B.Mask" "B.Paste")
			(net "GND")
		)
		(pad "5" smd rect
			(at -2.175002 1.050036)
			(size 0.6096 1.1684)
			(layers "B.Cu" "B.Mask" "B.Paste")
			(net "MB_I2C_ISO_EN")
		)
		(pad "6" smd rect
			(at -2.175002 0.32512)
			(size 0.4318 1.1684)
			(layers "B.Cu" "B.Mask" "B.Paste")
			(net "SMB_MB_BMC_R_SDA")
		)
		(pad "7" smd rect
			(at -2.175002 -0.32512)
			(size 0.4318 1.1684)
			(layers "B.Cu" "B.Mask" "B.Paste")
			(net "SMB_MB_BMC_R_SCL")
		)
		(pad "8" smd rect
			(at -2.175002 -1.050036)
			(size 0.6096 1.1684)
			(layers "B.Cu" "B.Mask" "B.Paste")
			(net "P3V3_AUX")
		)
	)
	(footprint ""
		(layer "B.Cu")
		(at 289.94989 -288.299906 90)
		(property "Reference" "C3268"
			(at 0 0 90)
			(layer "B.SilkS")
			(hide yes)
			(effects
				(font
					(size 1.27 1.27)
				)
				(justify mirror)
			)
		)
		(property "Value" ""
			(at 0 0 90)
			(layer "B.Fab")
			(effects
				(font
					(size 1.27 1.27)
				)
				(justify mirror)
			)
		)
		(duplicate_pad_numbers_are_jumpers no)
		(fp_line
			(start 0.299974 -0.150114)
			(end -0.299974 -0.150114)
			(stroke
				(width 0.1)
				(type default)
			)
			(layer "B.Fab")
		)
		(fp_line
			(start -0.299974 -0.150114)
			(end -0.299974 0.150114)
			(stroke
				(width 0.1)
				(type default)
			)
			(layer "B.Fab")
		)
		(fp_line
			(start 0.299974 0.150114)
			(end 0.299974 -0.150114)
			(stroke
				(width 0.1)
				(type default)
			)
			(layer "B.Fab")
		)
		(fp_line
			(start -0.299974 0.150114)
			(end 0.299974 0.150114)
			(stroke
				(width 0.1)
				(type default)
			)
			(layer "B.Fab")
		)
		(pad "1" smd rect
			(at 0.2667 0 270)
			(size 0.3048 0.381)
			(layers "B.Cu" "B.Mask" "B.Paste")
			(net "P1V25_PEX2")
		)
		(pad "2" smd rect
			(at -0.2667 0 270)
			(size 0.3048 0.381)
			(layers "B.Cu" "B.Mask" "B.Paste")
			(net "GND")
		)
	)
	(footprint ""
		(layer "B.Cu")
		(at 407.020268 -296.37482)
		(property "Reference" "C1877"
			(at 0 0 0)
			(layer "B.SilkS")
			(hide yes)
			(effects
				(font
					(size 1.27 1.27)
				)
				(justify mirror)
			)
		)
		(property "Value" ""
			(at 0 0 0)
			(layer "B.Fab")
			(effects
				(font
					(size 1.27 1.27)
				)
				(justify mirror)
			)
		)
		(duplicate_pad_numbers_are_jumpers no)
		(fp_line
			(start -0.299974 -0.150114)
			(end -0.299974 0.150114)
			(stroke
				(width 0.1)
				(type default)
			)
			(layer "B.Fab")
		)
		(fp_line
			(start -0.299974 0.150114)
			(end 0.299974 0.150114)
			(stroke
				(width 0.1)
				(type default)
			)
			(layer "B.Fab")
		)
		(fp_line
			(start 0.299974 -0.150114)
			(end -0.299974 -0.150114)
			(stroke
				(width 0.1)
				(type default)
			)
			(layer "B.Fab")
		)
		(fp_line
			(start 0.299974 0.150114)
			(end 0.299974 -0.150114)
			(stroke
				(width 0.1)
				(type default)
			)
			(layer "B.Fab")
		)
		(pad "1" smd rect
			(at 0.2667 0 180)
			(size 0.3048 0.381)
			(layers "B.Cu" "B.Mask" "B.Paste")
			(net "P0V8_PEX3")
		)
		(pad "2" smd rect
			(at -0.2667 0 180)
			(size 0.3048 0.381)
			(layers "B.Cu" "B.Mask" "B.Paste")
			(net "GND")
		)
	)
	(footprint ""
		(layer "B.Cu")
		(at 101.408484 -308.436772 90)
		(property "Reference" "C4195"
			(at 0 0 90)
			(layer "B.SilkS")
			(hide yes)
			(effects
				(font
					(size 1.27 1.27)
				)
				(justify mirror)
			)
		)
		(property "Value" ""
			(at 0 0 90)
			(layer "B.Fab")
			(effects
				(font
					(size 1.27 1.27)
				)
				(justify mirror)
			)
		)
		(duplicate_pad_numbers_are_jumpers no)
		(fp_line
			(start 0.299974 -0.150114)
			(end -0.299974 -0.150114)
			(stroke
				(width 0.1)
				(type default)
			)
			(layer "B.Fab")
		)
		(fp_line
			(start -0.299974 -0.150114)
			(end -0.299974 0.150114)
			(stroke
				(width 0.1)
				(type default)
			)
			(layer "B.Fab")
		)
		(fp_line
			(start 0.299974 0.150114)
			(end 0.299974 -0.150114)
			(stroke
				(width 0.1)
				(type default)
			)
			(layer "B.Fab")
		)
		(fp_line
			(start -0.299974 0.150114)
			(end 0.299974 0.150114)
			(stroke
				(width 0.1)
				(type default)
			)
			(layer "B.Fab")
		)
		(pad "1" smd rect
			(at 0.2667 0 270)
			(size 0.3048 0.381)
			(layers "B.Cu" "B.Mask" "B.Paste")
			(net "P0V8_PEX0")
		)
		(pad "2" smd rect
			(at -0.2667 0 270)
			(size 0.3048 0.381)
			(layers "B.Cu" "B.Mask" "B.Paste")
			(net "GND")
		)
	)
	(footprint ""
		(layer "B.Cu")
		(at 118.61165 -321.396106 -90)
		(property "Reference" "R6483"
			(at 0 0 90)
			(layer "B.SilkS")
			(hide yes)
			(effects
				(font
					(size 1.27 1.27)
				)
				(justify mirror)
			)
		)
		(property "Value" ""
			(at 0 0 90)
			(layer "B.Fab")
			(effects
				(font
					(size 1.27 1.27)
				)
				(justify mirror)
			)
		)
		(duplicate_pad_numbers_are_jumpers no)
		(fp_line
			(start -0.7874 0.4064)
			(end 0.7874 0.4064)
			(stroke
				(width 0.1524)
				(type default)
			)
			(layer "B.SilkS")
		)
		(fp_line
			(start 0.7874 0.4064)
			(end 0.7874 -0.4064)
			(stroke
				(width 0.1524)
				(type default)
			)
			(layer "B.SilkS")
		)
		(fp_line
			(start -0.7874 -0.4064)
			(end -0.7874 0.4064)
			(stroke
				(width 0.1524)
				(type default)
			)
			(layer "B.SilkS")
		)
		(fp_line
			(start 0.7874 -0.4064)
			(end -0.7874 -0.4064)
			(stroke
				(width 0.1524)
				(type default)
			)
			(layer "B.SilkS")
		)
		(fp_line
			(start -0.67945 0.3048)
			(end -0.120396 0.3048)
			(stroke
				(width 0.1)
				(type default)
			)
			(layer "B.Fab")
		)
		(fp_line
			(start -0.120396 0.3048)
			(end -0.120396 0.2794)
			(stroke
				(width 0.1)
				(type default)
			)
			(layer "B.Fab")
		)
		(fp_line
			(start 0.12065 0.3048)
			(end 0.67945 0.3048)
			(stroke
				(width 0.1)
				(type default)
			)
			(layer "B.Fab")
		)
		(fp_line
			(start 0.67945 0.3048)
			(end 0.67945 -0.305054)
			(stroke
				(width 0.1)
				(type default)
			)
			(layer "B.Fab")
		)
		(fp_line
			(start -0.120396 0.2794)
			(end 0.12065 0.2794)
			(stroke
				(width 0.1)
				(type default)
			)
			(layer "B.Fab")
		)
		(fp_line
			(start 0.12065 0.2794)
			(end 0.12065 0.3048)
			(stroke
				(width 0.1)
				(type default)
			)
			(layer "B.Fab")
		)
		(fp_line
			(start -0.12065 -0.2794)
			(end -0.12065 -0.3048)
			(stroke
				(width 0.1)
				(type default)
			)
			(layer "B.Fab")
		)
		(fp_line
			(start 0.12065 -0.2794)
			(end -0.12065 -0.2794)
			(stroke
				(width 0.1)
				(type default)
			)
			(layer "B.Fab")
		)
		(fp_line
			(start -0.67945 -0.3048)
			(end -0.67945 0.3048)
			(stroke
				(width 0.1)
				(type default)
			)
			(layer "B.Fab")
		)
		(fp_line
			(start -0.12065 -0.3048)
			(end -0.67945 -0.3048)
			(stroke
				(width 0.1)
				(type default)
			)
			(layer "B.Fab")
		)
		(fp_line
			(start 0.12065 -0.305054)
			(end 0.12065 -0.2794)
			(stroke
				(width 0.1)
				(type default)
			)
			(layer "B.Fab")
		)
		(fp_line
			(start 0.67945 -0.305054)
			(end 0.12065 -0.305054)
			(stroke
				(width 0.1)
				(type default)
			)
			(layer "B.Fab")
		)
		(pad "1" smd circle
			(at 0.40005 0 90)
			(size 0 0)
			(layers "B.Cu" "B.Mask" "B.Paste")
			(net "P0V8_SERDES_VDDA_PEX1")
		)
		(pad "2" smd circle
			(at -0.40005 0 90)
			(size 0 0)
			(layers "B.Cu" "B.Mask" "B.Paste")
			(net "P0V8_SERDES_VDDA_PEX1_C6")
		)
	)
)
